(kicad_pcb
	(version 20260206)
	(generator "pcbnew")
	(generator_version "10.0")
	(general
		(thickness 1.6)
		(legacy_teardrops no)
	)
	(paper "A4")
	(title_block
		(title "04192023_DAF0TMB3IC0_F0TG_MB_C_brd_V02_OCP.brd")
		(comment 1 "Grand Teton / footprints 3575-3578 of 8354")
	)
	(layers
		(0 "F.Cu" signal "TOP")
		(4 "In1.Cu" signal "GND")
		(6 "In2.Cu" signal "IN1")
		(8 "In3.Cu" signal "GND1")
		(10 "In4.Cu" signal "IN2")
		(12 "In5.Cu" signal "GND2")
		(14 "In6.Cu" signal "IN3")
		(16 "In7.Cu" signal "GND3")
		(18 "In8.Cu" signal "VCC")
		(20 "In9.Cu" signal "VCC1")
		(22 "In10.Cu" signal "GND4")
		(24 "In11.Cu" signal "IN4")
		(26 "In12.Cu" signal "GND5")
		(28 "In13.Cu" signal "IN5")
		(30 "In14.Cu" signal "GND6")
		(32 "In15.Cu" signal "IN6")
		(34 "In16.Cu" signal "GND7")
		(2 "B.Cu" signal "BOTTOM")
		(9 "F.Adhes" user "F.Adhesive")
		(11 "B.Adhes" user "B.Adhesive")
		(13 "F.Paste" user "Package Geometry/Pastemask Top")
		(15 "B.Paste" user "Package Geometry/Pastemask Bottom")
		(5 "F.SilkS" user "Ref Des/Silkscreen Top")
		(7 "B.SilkS" user "Ref Des/Silkscreen Bottom")
		(1 "F.Mask" user "Board Geometry/Soldermask Top")
		(3 "B.Mask" user "Board Geometry/Soldermask Bottom")
		(17 "Dwgs.User" user "User.Drawings")
		(19 "Cmts.User" user "User.Comments")
		(21 "Eco1.User" user "User.Eco1")
		(23 "Eco2.User" user "User.Eco2")
		(25 "Edge.Cuts" user "Board Geometry/Outline")
		(27 "Margin" user)
		(31 "F.CrtYd" user "Package Geometry/Place Bound Top")
		(29 "B.CrtYd" user "Package Geometry/Place Bound Bottom")
		(35 "F.Fab" user "Ref Des/Assembly Top")
		(33 "B.Fab" user "Ref Des/Assembly Bottom")
	)
	(footprint ""
		(layer "F.Cu")
		(at 90.819478 -149.96541 180)
		(property "Reference" "PR151"
			(at 0 0 180)
			(layer "F.SilkS")
			(hide yes)
			(effects
				(font
					(size 1.27 1.27)
				)
			)
		)
		(property "Value" ""
			(at 0 0 180)
			(layer "F.Fab")
			(effects
				(font
					(size 1.27 1.27)
				)
			)
		)
		(duplicate_pad_numbers_are_jumpers no)
		(fp_line
			(start 0.7874 0.4064)
			(end -0.7874 0.4064)
			(stroke
				(width 0.1524)
				(type default)
			)
			(layer "F.SilkS")
		)
		(fp_line
			(start 0.7874 -0.4064)
			(end 0.7874 0.4064)
			(stroke
				(width 0.1524)
				(type default)
			)
			(layer "F.SilkS")
		)
		(fp_line
			(start -0.7874 0.4064)
			(end -0.7874 -0.4064)
			(stroke
				(width 0.1524)
				(type default)
			)
			(layer "F.SilkS")
		)
		(fp_line
			(start -0.7874 -0.4064)
			(end 0.7874 -0.4064)
			(stroke
				(width 0.1524)
				(type default)
			)
			(layer "F.SilkS")
		)
		(fp_line
			(start 0.67945 0.3048)
			(end 0.120396 0.3048)
			(stroke
				(width 0.1)
				(type default)
			)
			(layer "F.Fab")
		)
		(fp_line
			(start 0.67945 -0.3048)
			(end 0.67945 0.3048)
			(stroke
				(width 0.1)
				(type default)
			)
			(layer "F.Fab")
		)
		(fp_line
			(start 0.12065 -0.2794)
			(end 0.12065 -0.3048)
			(stroke
				(width 0.1)
				(type default)
			)
			(layer "F.Fab")
		)
		(fp_line
			(start 0.12065 -0.3048)
			(end 0.67945 -0.3048)
			(stroke
				(width 0.1)
				(type default)
			)
			(layer "F.Fab")
		)
		(fp_line
			(start 0.120396 0.3048)
			(end 0.120396 0.2794)
			(stroke
				(width 0.1)
				(type default)
			)
			(layer "F.Fab")
		)
		(fp_line
			(start 0.120396 0.2794)
			(end -0.12065 0.2794)
			(stroke
				(width 0.1)
				(type default)
			)
			(layer "F.Fab")
		)
		(fp_line
			(start -0.12065 0.3048)
			(end -0.67945 0.3048)
			(stroke
				(width 0.1)
				(type default)
			)
			(layer "F.Fab")
		)
		(fp_line
			(start -0.12065 0.2794)
			(end -0.12065 0.3048)
			(stroke
				(width 0.1)
				(type default)
			)
			(layer "F.Fab")
		)
		(fp_line
			(start -0.12065 -0.2794)
			(end 0.12065 -0.2794)
			(stroke
				(width 0.1)
				(type default)
			)
			(layer "F.Fab")
		)
		(fp_line
			(start -0.12065 -0.305054)
			(end -0.12065 -0.2794)
			(stroke
				(width 0.1)
				(type default)
			)
			(layer "F.Fab")
		)
		(fp_line
			(start -0.67945 0.3048)
			(end -0.67945 -0.305054)
			(stroke
				(width 0.1)
				(type default)
			)
			(layer "F.Fab")
		)
		(fp_line
			(start -0.67945 -0.305054)
			(end -0.12065 -0.305054)
			(stroke
				(width 0.1)
				(type default)
			)
			(layer "F.Fab")
		)
		(pad "1" smd circle
			(at -0.40005 0 180)
			(size 0 0)
			(layers "F.Cu" "F.Mask" "F.Paste")
			(net "PVDD18_S5_P1")
		)
		(pad "2" smd circle
			(at 0.40005 0 180)
			(size 0 0)
			(layers "F.Cu" "F.Mask" "F.Paste")
			(net "SVID_PVDDCR_CPU0_P1_SVTI")
		)
	)
	(footprint ""
		(layer "F.Cu")
		(at 180.824378 -153.632662 -90)
		(property "Reference" "C42"
			(at 0 0 270)
			(layer "F.SilkS")
			(hide yes)
			(effects
				(font
					(size 1.27 1.27)
				)
			)
		)
		(property "Value" ""
			(at 0 0 270)
			(layer "F.Fab")
			(effects
				(font
					(size 1.27 1.27)
				)
			)
		)
		(duplicate_pad_numbers_are_jumpers no)
		(fp_line
			(start -0.7874 0.4064)
			(end -0.7874 -0.4064)
			(stroke
				(width 0.1524)
				(type default)
			)
			(layer "F.SilkS")
		)
		(fp_line
			(start 0.7874 0.4064)
			(end -0.7874 0.4064)
			(stroke
				(width 0.1524)
				(type default)
			)
			(layer "F.SilkS")
		)
		(fp_line
			(start -0.7874 -0.4064)
			(end 0.7874 -0.4064)
			(stroke
				(width 0.1524)
				(type default)
			)
			(layer "F.SilkS")
		)
		(fp_line
			(start 0.7874 -0.4064)
			(end 0.7874 0.4064)
			(stroke
				(width 0.1524)
				(type default)
			)
			(layer "F.SilkS")
		)
		(fp_line
			(start -0.67945 0.3048)
			(end -0.67945 -0.305054)
			(stroke
				(width 0.1)
				(type default)
			)
			(layer "F.Fab")
		)
		(fp_line
			(start -0.12065 0.3048)
			(end -0.67945 0.3048)
			(stroke
				(width 0.1)
				(type default)
			)
			(layer "F.Fab")
		)
		(fp_line
			(start 0.120396 0.3048)
			(end 0.120396 0.2794)
			(stroke
				(width 0.1)
				(type default)
			)
			(layer "F.Fab")
		)
		(fp_line
			(start 0.67945 0.3048)
			(end 0.120396 0.3048)
			(stroke
				(width 0.1)
				(type default)
			)
			(layer "F.Fab")
		)
		(fp_line
			(start -0.12065 0.2794)
			(end -0.12065 0.3048)
			(stroke
				(width 0.1)
				(type default)
			)
			(layer "F.Fab")
		)
		(fp_line
			(start 0.120396 0.2794)
			(end -0.12065 0.2794)
			(stroke
				(width 0.1)
				(type default)
			)
			(layer "F.Fab")
		)
		(fp_line
			(start -0.12065 -0.2794)
			(end 0.12065 -0.2794)
			(stroke
				(width 0.1)
				(type default)
			)
			(layer "F.Fab")
		)
		(fp_line
			(start 0.12065 -0.2794)
			(end 0.12065 -0.3048)
			(stroke
				(width 0.1)
				(type default)
			)
			(layer "F.Fab")
		)
		(fp_line
			(start 0.12065 -0.3048)
			(end 0.67945 -0.3048)
			(stroke
				(width 0.1)
				(type default)
			)
			(layer "F.Fab")
		)
		(fp_line
			(start 0.67945 -0.3048)
			(end 0.67945 0.3048)
			(stroke
				(width 0.1)
				(type default)
			)
			(layer "F.Fab")
		)
		(fp_line
			(start -0.67945 -0.305054)
			(end -0.12065 -0.305054)
			(stroke
				(width 0.1)
				(type default)
			)
			(layer "F.Fab")
		)
		(fp_line
			(start -0.12065 -0.305054)
			(end -0.12065 -0.2794)
			(stroke
				(width 0.1)
				(type default)
			)
			(layer "F.Fab")
		)
		(pad "1" smd circle
			(at -0.40005 0 270)
			(size 0 0)
			(layers "F.Cu" "F.Mask" "F.Paste")
			(net "PVDD18_S5_P0")
		)
		(pad "2" smd circle
			(at 0.40005 0 270)
			(size 0 0)
			(layers "F.Cu" "F.Mask" "F.Paste")
			(net "GND")
		)
	)
	(footprint ""
		(layer "F.Cu")
		(at 201.636884 -337.480148)
		(property "Reference" "PC126"
			(at 0 0 0)
			(layer "F.SilkS")
			(hide yes)
			(effects
				(font
					(size 1.27 1.27)
				)
			)
		)
		(property "Value" ""
			(at 0 0 0)
			(layer "F.Fab")
			(effects
				(font
					(size 1.27 1.27)
				)
			)
		)
		(duplicate_pad_numbers_are_jumpers no)
		(fp_line
			(start -0.7874 -0.4064)
			(end 0.7874 -0.4064)
			(stroke
				(width 0.1524)
				(type default)
			)
			(layer "F.SilkS")
		)
		(fp_line
			(start -0.7874 0.4064)
			(end -0.7874 -0.4064)
			(stroke
				(width 0.1524)
				(type default)
			)
			(layer "F.SilkS")
		)
		(fp_line
			(start 0.7874 -0.4064)
			(end 0.7874 0.4064)
			(stroke
				(width 0.1524)
				(type default)
			)
			(layer "F.SilkS")
		)
		(fp_line
			(start 0.7874 0.4064)
			(end -0.7874 0.4064)
			(stroke
				(width 0.1524)
				(type default)
			)
			(layer "F.SilkS")
		)
		(fp_line
			(start -0.67945 -0.305054)
			(end -0.12065 -0.305054)
			(stroke
				(width 0.1)
				(type default)
			)
			(layer "F.Fab")
		)
		(fp_line
			(start -0.67945 0.3048)
			(end -0.67945 -0.305054)
			(stroke
				(width 0.1)
				(type default)
			)
			(layer "F.Fab")
		)
		(fp_line
			(start -0.12065 -0.305054)
			(end -0.12065 -0.2794)
			(stroke
				(width 0.1)
				(type default)
			)
			(layer "F.Fab")
		)
		(fp_line
			(start -0.12065 -0.2794)
			(end 0.12065 -0.2794)
			(stroke
				(width 0.1)
				(type default)
			)
			(layer "F.Fab")
		)
		(fp_line
			(start -0.12065 0.2794)
			(end -0.12065 0.3048)
			(stroke
				(width 0.1)
				(type default)
			)
			(layer "F.Fab")
		)
		(fp_line
			(start -0.12065 0.3048)
			(end -0.67945 0.3048)
			(stroke
				(width 0.1)
				(type default)
			)
			(layer "F.Fab")
		)
		(fp_line
			(start 0.120396 0.2794)
			(end -0.12065 0.2794)
			(stroke
				(width 0.1)
				(type default)
			)
			(layer "F.Fab")
		)
		(fp_line
			(start 0.120396 0.3048)
			(end 0.120396 0.2794)
			(stroke
				(width 0.1)
				(type default)
			)
			(layer "F.Fab")
		)
		(fp_line
			(start 0.12065 -0.3048)
			(end 0.67945 -0.3048)
			(stroke
				(width 0.1)
				(type default)
			)
			(layer "F.Fab")
		)
		(fp_line
			(start 0.12065 -0.2794)
			(end 0.12065 -0.3048)
			(stroke
				(width 0.1)
				(type default)
			)
			(layer "F.Fab")
		)
		(fp_line
			(start 0.67945 -0.3048)
			(end 0.67945 0.3048)
			(stroke
				(width 0.1)
				(type default)
			)
			(layer "F.Fab")
		)
		(fp_line
			(start 0.67945 0.3048)
			(end 0.120396 0.3048)
			(stroke
				(width 0.1)
				(type default)
			)
			(layer "F.Fab")
		)
		(pad "1" smd circle
			(at -0.40005 0)
			(size 0 0)
			(layers "F.Cu" "F.Mask" "F.Paste")
			(net "SW_P12V_AUX_PVDD_33_S5_FLT")
		)
		(pad "2" smd circle
			(at 0.40005 0)
			(size 0 0)
			(layers "F.Cu" "F.Mask" "F.Paste")
			(net "GND")
		)
	)
	(footprint ""
		(layer "F.Cu")
		(at 124.633228 -48.137064)
		(property "Reference" "R4451"
			(at 0 0 0)
			(layer "F.SilkS")
			(hide yes)
			(effects
				(font
					(size 1.27 1.27)
				)
			)
		)
		(property "Value" ""
			(at 0 0 0)
			(layer "F.Fab")
			(effects
				(font
					(size 1.27 1.27)
				)
			)
		)
		(duplicate_pad_numbers_are_jumpers no)
		(fp_line
			(start -0.7874 -0.4064)
			(end 0.7874 -0.4064)
			(stroke
				(width 0.1524)
				(type default)
			)
			(layer "F.SilkS")
		)
		(fp_line
			(start -0.7874 0.4064)
			(end -0.7874 -0.4064)
			(stroke
				(width 0.1524)
				(type default)
			)
			(layer "F.SilkS")
		)
		(fp_line
			(start 0.7874 -0.4064)
			(end 0.7874 0.4064)
			(stroke
				(width 0.1524)
				(type default)
			)
			(layer "F.SilkS")
		)
		(fp_line
			(start 0.7874 0.4064)
			(end -0.7874 0.4064)
			(stroke
				(width 0.1524)
				(type default)
			)
			(layer "F.SilkS")
		)
		(fp_line
			(start -0.67945 -0.305054)
			(end -0.12065 -0.305054)
			(stroke
				(width 0.1)
				(type default)
			)
			(layer "F.Fab")
		)
		(fp_line
			(start -0.67945 0.3048)
			(end -0.67945 -0.305054)
			(stroke
				(width 0.1)
				(type default)
			)
			(layer "F.Fab")
		)
		(fp_line
			(start -0.12065 -0.305054)
			(end -0.12065 -0.2794)
			(stroke
				(width 0.1)
				(type default)
			)
			(layer "F.Fab")
		)
		(fp_line
			(start -0.12065 -0.2794)
			(end 0.12065 -0.2794)
			(stroke
				(width 0.1)
				(type default)
			)
			(layer "F.Fab")
		)
		(fp_line
			(start -0.12065 0.2794)
			(end -0.12065 0.3048)
			(stroke
				(width 0.1)
				(type default)
			)
			(layer "F.Fab")
		)
		(fp_line
			(start -0.12065 0.3048)
			(end -0.67945 0.3048)
			(stroke
				(width 0.1)
				(type default)
			)
			(layer "F.Fab")
		)
		(fp_line
			(start 0.120396 0.2794)
			(end -0.12065 0.2794)
			(stroke
				(width 0.1)
				(type default)
			)
			(layer "F.Fab")
		)
		(fp_line
			(start 0.120396 0.3048)
			(end 0.120396 0.2794)
			(stroke
				(width 0.1)
				(type default)
			)
			(layer "F.Fab")
		)
		(fp_line
			(start 0.12065 -0.3048)
			(end 0.67945 -0.3048)
			(stroke
				(width 0.1)
				(type default)
			)
			(layer "F.Fab")
		)
		(fp_line
			(start 0.12065 -0.2794)
			(end 0.12065 -0.3048)
			(stroke
				(width 0.1)
				(type default)
			)
			(layer "F.Fab")
		)
		(fp_line
			(start 0.67945 -0.3048)
			(end 0.67945 0.3048)
			(stroke
				(width 0.1)
				(type default)
			)
			(layer "F.Fab")
		)
		(fp_line
			(start 0.67945 0.3048)
			(end 0.120396 0.3048)
			(stroke
				(width 0.1)
				(type default)
			)
			(layer "F.Fab")
		)
		(pad "1" smd circle
			(at -0.40005 0)
			(size 0 0)
			(layers "F.Cu" "F.Mask" "F.Paste")
			(net "RST_USB_HUB_N")
		)
		(pad "2" smd circle
			(at 0.40005 0)
			(size 0 0)
			(layers "F.Cu" "F.Mask" "F.Paste")
			(net "RST_USB_CPU0_HUB1_R_N")
		)
	)
)
